# TIMECARD (Time Appliance Project (Time Card)) — schematic netlist excerpt (pin names and nets, part order shuffled) for the footprints in the layout excerpt that follows; sources: Cadence DE-HDL packaged netlist, KiCad conversion of R4006-B0001-02_R01.brd

ME6  MEC_NPTH  pkg MTH100C240N  page 34
R422  RESISTOR  4.7KOHM 1%  pkg SMC_0402R_H016  page 17 : \1\ = XP3R3V_FPGA ; \2\ = FPGA_IN_LM75B_INT2_N

(kicad_pcb
	(version 20260206)
	(generator "pcbnew")
	(generator_version "10.0")
	(general
		(thickness 1.6)
		(legacy_teardrops no)
	)
	(paper "A4")
	(title_block
		(title "timecard-production-celestica-r4006 — R4006-B0001-02_R01.brd")
		(comment 1 "Time Appliance Project (Time Card) / footprints 151-152 of 1113")
	)
	(layers
		(0 "F.Cu" signal "TOP")
		(4 "In1.Cu" signal "L02_GND1")
		(6 "In2.Cu" signal "L03_SIG1")
		(8 "In3.Cu" signal "L04_GND2")
		(10 "In4.Cu" signal "L05_VCC1")
		(12 "In5.Cu" signal "L06_VCC2")
		(14 "In6.Cu" signal "L07_GND3")
		(16 "In7.Cu" signal "L08_SIG2")
		(18 "In8.Cu" signal "L09_GND4")
		(2 "B.Cu" signal "BOTTOM")
		(9 "F.Adhes" user "F.Adhesive")
		(11 "B.Adhes" user "B.Adhesive")
		(13 "F.Paste" user "Package Geometry/Pastemask Top")
		(15 "B.Paste" user "Package Geometry/Pastemask Bottom")
		(5 "F.SilkS" user "Ref Des/Silkscreen Top")
		(7 "B.SilkS" user "Ref Des/Silkscreen Bottom")
		(1 "F.Mask" user "Board Geometry/Soldermask Top")
		(3 "B.Mask" user "Board Geometry/Soldermask Bottom")
		(17 "Dwgs.User" user "User.Drawings")
		(19 "Cmts.User" user "User.Comments")
		(21 "Eco1.User" user "User.Eco1")
		(23 "Eco2.User" user "User.Eco2")
		(25 "Edge.Cuts" user "Board Geometry/Outline")
		(27 "Margin" user)
		(31 "F.CrtYd" user "Package Geometry/Place Bound Top")
		(29 "B.CrtYd" user "Package Geometry/Place Bound Bottom")
		(35 "F.Fab" user "Ref Des/Assembly Top")
		(33 "B.Fab" user "Ref Des/Assembly Bottom")
	)
	(footprint ""
		(layer "F.Cu")
		(at 49.7586 -83.0072 -90)
		(property "Reference" "R422"
			(at -3.3528 -0.19177 90)
			(unlocked yes)
			(layer "F.SilkS")
			(effects
				(font
					(size 0.7874 0.5842)
					(thickness 0.1524)
				)
			)
		)
		(property "Value" "VAL*"
			(at 0.02032 2.13233 270)
			(unlocked yes)
			(layer "F.Fab")
			(hide yes)
			(effects
				(font
					(size 0.7874 0.5842)
					(thickness 0.1524)
				)
			)
		)
		(property "Tolerance" "TOL*"
			(at 0.044704 3.05435 270)
			(unlocked yes)
			(layer "Cmts.User")
			(hide yes)
			(effects
				(font
					(size 0.7874 0.5842)
					(thickness 0.1524)
				)
			)
		)
		(property "User Part Number" "PARTNUM*"
			(at 0.02032 4.024884 270)
			(unlocked yes)
			(layer "Cmts.User")
			(hide yes)
			(effects
				(font
					(size 0.7874 0.5842)
					(thickness 0.1524)
				)
			)
		)
		(property "Device Type" "RESISTOR-G155-14701-01,4.7KOHMA"
			(at 0.008382 1.210564 270)
			(unlocked yes)
			(layer "F.Fab")
			(hide yes)
			(effects
				(font
					(size 0.7874 0.5842)
					(thickness 0.1524)
				)
			)
		)
		(duplicate_pad_numbers_are_jumpers no)
		(fp_line
			(start -1.143 0.5588)
			(end 1.143 0.5588)
			(stroke
				(width 0.1)
				(type default)
			)
			(layer "F.SilkS")
		)
		(fp_line
			(start 1.143 0.5588)
			(end 1.143 -0.5588)
			(stroke
				(width 0.1)
				(type default)
			)
			(layer "F.SilkS")
		)
		(fp_line
			(start -1.143 -0.5588)
			(end -1.143 0.5588)
			(stroke
				(width 0.1)
				(type default)
			)
			(layer "F.SilkS")
		)
		(fp_line
			(start 1.143 -0.5588)
			(end -1.143 -0.5588)
			(stroke
				(width 0.1)
				(type default)
			)
			(layer "F.SilkS")
		)
		(fp_rect
			(start -1.143 0.5588)
			(end 1.143 -0.5588)
			(stroke
				(width 0)
				(type default)
			)
			(fill no)
			(layer "F.CrtYd")
		)
		(fp_line
			(start -0.508 0.3048)
			(end 0.508 0.3048)
			(stroke
				(width 0.1)
				(type default)
			)
			(layer "F.Fab")
		)
		(fp_line
			(start 0.508 0.3048)
			(end 0.508 -0.3048)
			(stroke
				(width 0.1)
				(type default)
			)
			(layer "F.Fab")
		)
		(fp_line
			(start -0.508 -0.3048)
			(end -0.508 0.3048)
			(stroke
				(width 0.1)
				(type default)
			)
			(layer "F.Fab")
		)
		(fp_line
			(start 0.508 -0.3048)
			(end -0.508 -0.3048)
			(stroke
				(width 0.1)
				(type default)
			)
			(layer "F.Fab")
		)
		(pad "1" smd rect
			(at -0.5334 0 270)
			(size 0.7112 0.6096)
			(layers "F.Cu" "F.Mask" "F.Paste")
			(net "XP3R3V_FPGA")
		)
		(pad "2" smd rect
			(at 0.5334 0 270)
			(size 0.7112 0.6096)
			(layers "F.Cu" "F.Mask" "F.Paste")
			(net "FPGA_IN_LM75B_INT2_N")
		)
		(zone
			(layer "F.Cu")
			(hatch none 0.5)
			(connect_pads
				(clearance 0)
			)
			(min_thickness 0.25)
			(keepout
				(tracks not_allowed)
				(vias allowed)
				(pads allowed)
				(copperpour not_allowed)
				(footprints allowed)
			)
			(placement
				(enabled no)
				(sheetname "")
			)
			(fill
				(thermal_gap 0.5)
				(thermal_bridge_width 0.5)
				(island_removal_mode 0)
			)
			(polygon
				(pts
					(xy 49.4538 -83.0834) (xy 49.4538 -82.931) (xy 50.0634 -82.931) (xy 50.0634 -83.0834)
				)
			)
		)
		(zone
			(layer "F.Cu")
			(hatch none 0.5)
			(connect_pads
				(clearance 0)
			)
			(min_thickness 0.25)
			(keepout
				(tracks allowed)
				(vias not_allowed)
				(pads allowed)
				(copperpour not_allowed)
				(footprints allowed)
			)
			(placement
				(enabled no)
				(sheetname "")
			)
			(fill
				(thermal_gap 0.5)
				(thermal_bridge_width 0.5)
				(island_removal_mode 0)
			)
			(polygon
				(pts
					(xy 49.4538 -83.0834) (xy 49.4538 -82.931) (xy 50.0634 -82.931) (xy 50.0634 -83.0834)
				)
			)
		)
	)
	(footprint ""
		(layer "F.Cu")
		(at 68.216018 -65.009522)
		(property "Reference" "ME6"
			(at -4.444238 2.072132 0)
			(unlocked yes)
			(layer "F.SilkS")
			(effects
				(font
					(size 0.7874 0.5842)
					(thickness 0.1524)
				)
			)
		)
		(property "Value" ""
			(at 0 0 0)
			(layer "F.Fab")
			(effects
				(font
					(size 1.27 1.27)
				)
			)
		)
		(duplicate_pad_numbers_are_jumpers no)
		(fp_poly
			(pts
				(arc
					(start 3.556 0)
					(mid -3.556 0)
					(end 3.556 0)
				)
			)
			(stroke
				(width 0)
				(type default)
			)
			(fill no)
			(layer "B.CrtYd")
		)
		(fp_poly
			(pts
				(arc
					(start 3.556 0)
					(mid -3.556 0)
					(end 3.556 0)
				)
			)
			(stroke
				(width 0)
				(type default)
			)
			(fill no)
			(layer "F.CrtYd")
		)
		(fp_circle
			(center 0 0)
			(end 3.048 0)
			(stroke
				(width 0.1)
				(type default)
			)
			(fill no)
			(layer "B.Fab")
		)
		(fp_circle
			(center 0 0)
			(end 3.048 0)
			(stroke
				(width 0.1)
				(type default)
			)
			(fill no)
			(layer "F.Fab")
		)
		(pad "" np_thru_hole circle
			(at 0 0)
			(size 2.286 2.286)
			(drill 2.54)
			(layers "*.Cu" "*.Mask")
			(padstack
				(mode front_inner_back)
				(layer "Inner"
					(shape circle)
					(size 2.286 2.286)
					(clearance 0.4445)
				)
				(layer "B.Cu"
					(shape circle)
					(size 2.286 2.286)
				)
			)
		)
		(zone
			(layers "F.Cu" "B.Cu" "In1.Cu" "In2.Cu" "In3.Cu" "In4.Cu" "In5.Cu" "In6.Cu"
				"In7.Cu" "In8.Cu"
			)
			(hatch none 0.5)
			(connect_pads
				(clearance 0)
			)
			(min_thickness 0.25)
			(keepout
				(tracks not_allowed)
				(vias allowed)
				(pads allowed)
				(copperpour not_allowed)
				(footprints allowed)
			)
			(placement
				(enabled no)
				(sheetname "")
			)
			(fill
				(thermal_gap 0.5)
				(thermal_bridge_width 0.5)
				(island_removal_mode 0)
			)
			(polygon
				(pts
					(arc
						(start 69.790818 -65.009522)
						(mid 66.641218 -65.009522)
						(end 69.790818 -65.009522)
					)
				)
			)
		)
	)
)
